# BASEBOARD_FAB2 (Tioga Pass) — schematic netlist excerpt (pin names and nets, part order shuffled) for the footprints in the layout excerpt that follows; sources: Cadence DE-HDL packaged netlist, KiCad conversion of Wiwynn_Tioga_Pass_MB.brd

R1L36  RES  1.00K 1% CHIP  pkg 0402  page 168 : A = P3V3_STBY ; B = FM_DB_PRESENT
C25W26  CAP  1.0UF 16V 10% X6S  pkg 0402  page 149 : A = P1V15_AUX_BMC ; B = GND
C2N16  CAP_A  1.0UF 6.3V 10% X6S  pkg 0402V  page 130 : A = P1V8_PCH_STBY ; B = GND

(kicad_pcb
	(version 20260206)
	(generator "pcbnew")
	(generator_version "10.0")
	(general
		(thickness 1.6)
		(legacy_teardrops no)
	)
	(paper "A4")
	(title_block
		(title "Wiwynn_Tioga_Pass_MB.brd")
		(comment 1 "Tioga Pass / footprints 2342-2344 of 4770")
	)
	(layers
		(0 "F.Cu" signal "TOP")
		(4 "In1.Cu" signal "L2GND")
		(6 "In2.Cu" signal "L3")
		(8 "In3.Cu" signal "L4GND")
		(10 "In4.Cu" signal "L5")
		(12 "In5.Cu" signal "L6GND")
		(14 "In6.Cu" signal "L7VCC")
		(16 "In7.Cu" signal "L8VCC")
		(18 "In8.Cu" signal "L9GND")
		(20 "In9.Cu" signal "L10")
		(22 "In10.Cu" signal "L11GND")
		(24 "In11.Cu" signal "L12")
		(26 "In12.Cu" signal "L13GND")
		(2 "B.Cu" signal "BOTTOM")
		(9 "F.Adhes" user "F.Adhesive")
		(11 "B.Adhes" user "B.Adhesive")
		(13 "F.Paste" user "Package Geometry/Pastemask Top")
		(15 "B.Paste" user "Package Geometry/Pastemask Bottom")
		(5 "F.SilkS" user "Ref Des/Silkscreen Top")
		(7 "B.SilkS" user "Ref Des/Silkscreen Bottom")
		(1 "F.Mask" user "Board Geometry/Soldermask Top")
		(3 "B.Mask" user "Board Geometry/Soldermask Bottom")
		(17 "Dwgs.User" user "User.Drawings")
		(19 "Cmts.User" user "User.Comments")
		(21 "Eco1.User" user "User.Eco1")
		(23 "Eco2.User" user "User.Eco2")
		(25 "Edge.Cuts" user "Board Geometry/Outline")
		(27 "Margin" user)
		(31 "F.CrtYd" user "Package Geometry/Place Bound Top")
		(29 "B.CrtYd" user "Package Geometry/Place Bound Bottom")
		(35 "F.Fab" user "Ref Des/Assembly Top")
		(33 "B.Fab" user "Ref Des/Assembly Bottom")
	)
	(footprint ""
		(layer "B.Cu")
		(at 487.045 -140.8176 90)
		(property "Reference" "R1L36"
			(at 0 0 90)
			(layer "B.SilkS")
			(hide yes)
			(effects
				(font
					(size 1.27 1.27)
				)
				(justify mirror)
			)
		)
		(property "Value" ""
			(at 0 0 90)
			(layer "B.Fab")
			(effects
				(font
					(size 1.27 1.27)
				)
				(justify mirror)
			)
		)
		(duplicate_pad_numbers_are_jumpers no)
		(fp_poly
			(pts
				(xy 0.2794 -0.1016) (xy -0.2794 -0.1016) (xy -0.2794 0.9906) (xy 0.2794 0.9906)
			)
			(stroke
				(width 0)
				(type default)
			)
			(fill no)
			(layer "B.CrtYd")
		)
		(fp_line
			(start 0.2794 -0.1016)
			(end 0.2794 0.9906)
			(stroke
				(width 0.1)
				(type default)
			)
			(layer "B.Fab")
		)
		(fp_line
			(start -0.2794 -0.1016)
			(end 0.2794 -0.1016)
			(stroke
				(width 0.1)
				(type default)
			)
			(layer "B.Fab")
		)
		(fp_line
			(start 0.2794 0.9906)
			(end -0.2794 0.9906)
			(stroke
				(width 0.1)
				(type default)
			)
			(layer "B.Fab")
		)
		(fp_line
			(start -0.2794 0.9906)
			(end -0.2794 -0.1016)
			(stroke
				(width 0.1)
				(type default)
			)
			(layer "B.Fab")
		)
		(pad "1" smd rect
			(at 0 0 270)
			(size 0.508 0.508)
			(layers "B.Cu" "B.Mask" "B.Paste")
			(net "P3V3_STBY")
		)
		(pad "2" smd rect
			(at 0 0.889 270)
			(size 0.508 0.508)
			(layers "B.Cu" "B.Mask" "B.Paste")
			(net "FM_DB_PRESENT")
		)
		(zone
			(layer "B.Cu")
			(hatch none 0.5)
			(connect_pads
				(clearance 0)
			)
			(min_thickness 0.25)
			(keepout
				(tracks allowed)
				(vias not_allowed)
				(pads allowed)
				(copperpour not_allowed)
				(footprints allowed)
			)
			(placement
				(enabled no)
				(sheetname "")
			)
			(fill
				(thermal_gap 0.5)
				(thermal_bridge_width 0.5)
				(island_removal_mode 0)
			)
			(polygon
				(pts
					(xy 487.299 -141.0716) (xy 487.299 -140.5636) (xy 487.68 -140.5636) (xy 487.68 -141.0716)
				)
			)
		)
		(zone
			(layer "B.Cu")
			(hatch none 0.5)
			(connect_pads
				(clearance 0)
			)
			(min_thickness 0.25)
			(keepout
				(tracks not_allowed)
				(vias allowed)
				(pads allowed)
				(copperpour not_allowed)
				(footprints allowed)
			)
			(placement
				(enabled no)
				(sheetname "")
			)
			(fill
				(thermal_gap 0.5)
				(thermal_bridge_width 0.5)
				(island_removal_mode 0)
			)
			(polygon
				(pts
					(xy 487.68 -141.0716) (xy 487.68 -140.5636) (xy 487.299 -140.5636) (xy 487.299 -141.0716)
				)
			)
		)
	)
	(footprint ""
		(layer "B.Cu")
		(at 389.33755 -106.25455 180)
		(property "Reference" "C2N16"
			(at 0 0 0)
			(layer "B.SilkS")
			(hide yes)
			(effects
				(font
					(size 1.27 1.27)
				)
				(justify mirror)
			)
		)
		(property "Value" ""
			(at 0 0 0)
			(layer "B.Fab")
			(effects
				(font
					(size 1.27 1.27)
				)
				(justify mirror)
			)
		)
		(duplicate_pad_numbers_are_jumpers no)
		(fp_rect
			(start 0.2794 0.9144)
			(end -0.2794 -0.1143)
			(stroke
				(width 0)
				(type default)
			)
			(fill no)
			(layer "B.CrtYd")
		)
		(fp_line
			(start 0.2794 0.9144)
			(end 0.2794 -0.1143)
			(stroke
				(width 0.1)
				(type default)
			)
			(layer "B.Fab")
		)
		(fp_line
			(start 0.2794 -0.1143)
			(end -0.2794 -0.1143)
			(stroke
				(width 0.1)
				(type default)
			)
			(layer "B.Fab")
		)
		(fp_line
			(start -0.2794 0.9144)
			(end 0.2794 0.9144)
			(stroke
				(width 0.1)
				(type default)
			)
			(layer "B.Fab")
		)
		(fp_line
			(start -0.2794 -0.1143)
			(end -0.2794 0.9144)
			(stroke
				(width 0.1)
				(type default)
			)
			(layer "B.Fab")
		)
		(pad "1" smd custom
			(at 0 0 90)
			(size 0.10414 0.10414)
			(layers "B.Cu" "B.Mask" "B.Paste")
			(net "P1V8_PCH_STBY")
			(options
				(clearance outline)
				(anchor circle)
			)
			(primitives
				(gr_poly
					(pts
						(xy -0.20828 -0.08636) (xy -0.20828 0.08636) (xy -0.08636 0.20828) (xy 0.086614 0.20828) (xy 0.20828 0.086614)
						(xy 0.20828 -0.08636) (xy 0.08636 -0.20828) (xy -0.08636 -0.20828)
					)
					(width 0)
					(fill yes)
				)
			)
		)
		(pad "2" smd custom
			(at 0 0.8001 90)
			(size 0.10414 0.10414)
			(layers "B.Cu" "B.Mask" "B.Paste")
			(net "GND")
			(options
				(clearance outline)
				(anchor circle)
			)
			(primitives
				(gr_poly
					(pts
						(xy -0.20828 -0.08636) (xy -0.20828 0.08636) (xy -0.08636 0.20828) (xy 0.086614 0.20828) (xy 0.20828 0.086614)
						(xy 0.20828 -0.08636) (xy 0.08636 -0.20828) (xy -0.08636 -0.20828)
					)
					(width 0)
					(fill yes)
				)
			)
		)
		(zone
			(layer "B.Cu")
			(hatch none 0.5)
			(connect_pads
				(clearance 0)
			)
			(min_thickness 0.25)
			(keepout
				(tracks allowed)
				(vias not_allowed)
				(pads allowed)
				(copperpour not_allowed)
				(footprints allowed)
			)
			(placement
				(enabled no)
				(sheetname "")
			)
			(fill
				(thermal_gap 0.5)
				(thermal_bridge_width 0.5)
				(island_removal_mode 0)
			)
			(polygon
				(pts
					(xy 389.24992 -106.4641) (xy 389.24992 -106.8451) (xy 389.42518 -106.8451) (xy 389.425434 -106.4641)
				)
			)
		)
		(zone
			(layer "B.Cu")
			(hatch none 0.5)
			(connect_pads
				(clearance 0)
			)
			(min_thickness 0.25)
			(keepout
				(tracks not_allowed)
				(vias allowed)
				(pads allowed)
				(copperpour not_allowed)
				(footprints allowed)
			)
			(placement
				(enabled no)
				(sheetname "")
			)
			(fill
				(thermal_gap 0.5)
				(thermal_bridge_width 0.5)
				(island_removal_mode 0)
			)
			(polygon
				(pts
					(xy 389.24992 -106.4641) (xy 389.24992 -106.8451) (xy 389.42518 -106.8451) (xy 389.425434 -106.4641)
				)
			)
		)
	)
	(footprint ""
		(layer "B.Cu")
		(at 416.30092 -37.20338 -90)
		(property "Reference" "C25W26"
			(at 0.8382 -0.67818 270)
			(unlocked yes)
			(layer "B.SilkS")
			(effects
				(font
					(size 0.4064 0.254)
					(thickness 0.1524)
				)
				(justify left mirror)
			)
		)
		(property "Value" ""
			(at 0 0 90)
			(layer "B.Fab")
			(effects
				(font
					(size 1.27 1.27)
				)
				(justify mirror)
			)
		)
		(duplicate_pad_numbers_are_jumpers no)
		(fp_poly
			(pts
				(xy -0.3048 -0.1016) (xy -0.3048 0.9906) (xy 0.3048 0.9906) (xy 0.3048 -0.1016)
			)
			(stroke
				(width 0)
				(type default)
			)
			(fill no)
			(layer "B.CrtYd")
		)
		(fp_line
			(start -0.3048 0.9906)
			(end -0.3048 -0.1016)
			(stroke
				(width 0.1)
				(type default)
			)
			(layer "B.Fab")
		)
		(fp_line
			(start 0.3048 0.9906)
			(end -0.3048 0.9906)
			(stroke
				(width 0.1)
				(type default)
			)
			(layer "B.Fab")
		)
		(fp_line
			(start -0.3048 -0.1016)
			(end 0.3048 -0.1016)
			(stroke
				(width 0.1)
				(type default)
			)
			(layer "B.Fab")
		)
		(fp_line
			(start 0.3048 -0.1016)
			(end 0.3048 0.9906)
			(stroke
				(width 0.1)
				(type default)
			)
			(layer "B.Fab")
		)
		(pad "1" smd rect
			(at 0 0 90)
			(size 0.508 0.508)
			(layers "B.Cu" "B.Mask" "B.Paste")
			(net "P1V15_AUX_BMC")
		)
		(pad "2" smd rect
			(at 0 0.889 90)
			(size 0.508 0.508)
			(layers "B.Cu" "B.Mask" "B.Paste")
			(net "GND")
		)
		(zone
			(layer "B.Cu")
			(hatch none 0.5)
			(connect_pads
				(clearance 0)
			)
			(min_thickness 0.25)
			(keepout
				(tracks not_allowed)
				(vias allowed)
				(pads allowed)
				(copperpour not_allowed)
				(footprints allowed)
			)
			(placement
				(enabled no)
				(sheetname "")
			)
			(fill
				(thermal_gap 0.5)
				(thermal_bridge_width 0.5)
				(island_removal_mode 0)
			)
			(polygon
				(pts
					(xy 415.66592 -36.94938) (xy 415.66592 -37.45738) (xy 416.04692 -37.45738) (xy 416.04692 -36.94938)
				)
			)
		)
		(zone
			(layer "B.Cu")
			(hatch none 0.5)
			(connect_pads
				(clearance 0)
			)
			(min_thickness 0.25)
			(keepout
				(tracks allowed)
				(vias not_allowed)
				(pads allowed)
				(copperpour not_allowed)
				(footprints allowed)
			)
			(placement
				(enabled no)
				(sheetname "")
			)
			(fill
				(thermal_gap 0.5)
				(thermal_bridge_width 0.5)
				(island_removal_mode 0)
			)
			(polygon
				(pts
					(xy 416.04692 -36.94938) (xy 416.04692 -37.45738) (xy 415.66592 -37.45738) (xy 415.66592 -36.94938)
				)
			)
		)
	)
)
